(kicad_pcb
	(version 20260206)
	(generator "pcbnew")
	(generator_version "10.0")
	(general
		(thickness 1.6)
		(legacy_teardrops no)
	)
	(paper "A4")
	(title_block
		(title "baseboard — 13948-1b.1110WZS1818.brd")
		(comment 1 "Honey Badger (Wiwynn) / footprints 2097-2103 of 2523")
	)
	(layers
		(0 "F.Cu" signal "TOP")
		(4 "In1.Cu" signal "L2GND")
		(6 "In2.Cu" signal "L3")
		(8 "In3.Cu" signal "L4VCC")
		(10 "In4.Cu" signal "L5VCC")
		(12 "In5.Cu" signal "L6")
		(14 "In6.Cu" signal "L7GND")
		(2 "B.Cu" signal "BOTTOM")
		(9 "F.Adhes" user "F.Adhesive")
		(11 "B.Adhes" user "B.Adhesive")
		(13 "F.Paste" user "Package Geometry/Pastemask Top")
		(15 "B.Paste" user "Package Geometry/Pastemask Bottom")
		(5 "F.SilkS" user "Ref Des/Silkscreen Top")
		(7 "B.SilkS" user "Ref Des/Silkscreen Bottom")
		(1 "F.Mask" user "Board Geometry/Soldermask Top")
		(3 "B.Mask" user "Board Geometry/Soldermask Bottom")
		(17 "Dwgs.User" user "User.Drawings")
		(19 "Cmts.User" user "User.Comments")
		(21 "Eco1.User" user "User.Eco1")
		(23 "Eco2.User" user "User.Eco2")
		(25 "Edge.Cuts" user "Board Geometry/Outline")
		(27 "Margin" user)
		(31 "F.CrtYd" user "Package Geometry/Place Bound Top")
		(29 "B.CrtYd" user "Package Geometry/Place Bound Bottom")
		(35 "F.Fab" user "Ref Des/Assembly Top")
		(33 "B.Fab" user "Ref Des/Assembly Bottom")
	)
	(footprint ""
		(layer "B.Cu")
		(at 98.94316 -33.401 180)
		(property "Reference" "SC952"
			(at 0 0 0)
			(layer "B.SilkS")
			(hide yes)
			(effects
				(font
					(size 1.27 1.27)
				)
				(justify mirror)
			)
		)
		(property "Value" "SCD1U6D3V1KX-GP"
			(at 2.8321 -1.7399 180)
			(unlocked yes)
			(layer "B.Fab")
			(hide yes)
			(effects
				(font
					(size 1.016 1.016)
					(thickness 0.1524)
				)
				(justify mirror)
			)
		)
		(property "Device Type" "C0201H13"
			(at 2.8321 -3.2639 180)
			(unlocked yes)
			(layer "B.Fab")
			(hide yes)
			(effects
				(font
					(size 1.016 1.016)
					(thickness 0.1524)
				)
				(justify mirror)
			)
		)
		(duplicate_pad_numbers_are_jumpers no)
		(fp_rect
			(start 0.2794 0.6477)
			(end -0.2794 -0.6477)
			(stroke
				(width 0)
				(type default)
			)
			(fill no)
			(layer "B.CrtYd")
		)
		(fp_rect
			(start 0.2794 0.6477)
			(end -0.2794 -0.6477)
			(stroke
				(width 0)
				(type default)
			)
			(fill no)
			(layer "B.Fab")
		)
		(pad "1" smd custom
			(at 0 -0.2794)
			(size 0.0762 0.0762)
			(layers "B.Cu" "B.Mask" "B.Paste")
			(net "PCE_AVDD")
			(options
				(clearance outline)
				(anchor circle)
			)
			(primitives
				(gr_poly
					(pts
						(arc
							(start 0.1524 0.127)
							(mid 0.137521 0.162921)
							(end 0.1016 0.1778)
						)
						(arc
							(start -0.1016 0.1778)
							(mid -0.137521 0.162921)
							(end -0.1524 0.127)
						)
						(arc
							(start -0.1524 -0.127)
							(mid -0.137521 -0.162921)
							(end -0.1016 -0.1778)
						)
						(arc
							(start 0.1016 -0.1778)
							(mid 0.137521 -0.162921)
							(end 0.1524 -0.127)
						)
					)
					(width 0)
					(fill yes)
				)
			)
		)
		(pad "2" smd custom
			(at 0 0.2794)
			(size 0.0762 0.0762)
			(layers "B.Cu" "B.Mask" "B.Paste")
			(net "GND")
			(options
				(clearance outline)
				(anchor circle)
			)
			(primitives
				(gr_poly
					(pts
						(arc
							(start 0.1524 0.127)
							(mid 0.137521 0.162921)
							(end 0.1016 0.1778)
						)
						(arc
							(start -0.1016 0.1778)
							(mid -0.137521 0.162921)
							(end -0.1524 0.127)
						)
						(arc
							(start -0.1524 -0.127)
							(mid -0.137521 -0.162921)
							(end -0.1016 -0.1778)
						)
						(arc
							(start 0.1016 -0.1778)
							(mid 0.137521 -0.162921)
							(end 0.1524 -0.127)
						)
					)
					(width 0)
					(fill yes)
				)
			)
		)
	)
	(footprint ""
		(layer "B.Cu")
		(at 91.56954 -45.69714 90)
		(property "Reference" "SR650"
			(at 0 0 90)
			(layer "B.SilkS")
			(hide yes)
			(effects
				(font
					(size 1.27 1.27)
				)
				(justify mirror)
			)
		)
		(property "Value" "3KR2J-2-GP"
			(at -0.064008 -3.993896 90)
			(unlocked yes)
			(layer "B.Fab")
			(hide yes)
			(effects
				(font
					(size 1.016 1.016)
					(thickness 0.1524)
				)
				(justify mirror)
			)
		)
		(property "Device Type" "R402H16"
			(at -0.064008 -5.517896 90)
			(unlocked yes)
			(layer "B.Fab")
			(hide yes)
			(effects
				(font
					(size 1.016 1.016)
					(thickness 0.1524)
				)
				(justify mirror)
			)
		)
		(duplicate_pad_numbers_are_jumpers no)
		(fp_line
			(start 0.508 -0.9398)
			(end 0.508 0.9398)
			(stroke
				(width 0.1524)
				(type default)
			)
			(layer "B.SilkS")
		)
		(fp_line
			(start -0.508 -0.9398)
			(end 0.508 -0.9398)
			(stroke
				(width 0.1524)
				(type default)
			)
			(layer "B.SilkS")
		)
		(fp_rect
			(start 0.508 0.9398)
			(end -0.508 -0.9398)
			(stroke
				(width 0)
				(type default)
			)
			(fill no)
			(layer "B.CrtYd")
		)
		(fp_rect
			(start 0.508 0.9398)
			(end -0.508 -0.9398)
			(stroke
				(width 0)
				(type default)
			)
			(fill no)
			(layer "B.Fab")
		)
		(pad "1" smd custom
			(at 0 -0.4445 270)
			(size 0.1397 0.1397)
			(layers "B.Cu" "B.Mask" "B.Paste")
			(net "RTRIM")
			(options
				(clearance outline)
				(anchor circle)
			)
			(primitives
				(gr_poly
					(pts
						(arc
							(start -0.1778 0.2794)
							(mid -0.249642 0.249642)
							(end -0.2794 0.1778)
						)
						(arc
							(start -0.2794 -0.1778)
							(mid -0.249642 -0.249642)
							(end -0.1778 -0.2794)
						)
						(arc
							(start 0.1778 -0.2794)
							(mid 0.249642 -0.249642)
							(end 0.2794 -0.1778)
						)
						(arc
							(start 0.2794 0.1778)
							(mid 0.249642 0.249642)
							(end 0.1778 0.2794)
						)
					)
					(width 0)
					(fill yes)
				)
			)
		)
		(pad "2" smd custom
			(at 0 0.4445 270)
			(size 0.1397 0.1397)
			(layers "B.Cu" "B.Mask" "B.Paste")
			(net "RTRIM#")
			(options
				(clearance outline)
				(anchor circle)
			)
			(primitives
				(gr_poly
					(pts
						(arc
							(start -0.1778 0.2794)
							(mid -0.249642 0.249642)
							(end -0.2794 0.1778)
						)
						(arc
							(start -0.2794 -0.1778)
							(mid -0.249642 -0.249642)
							(end -0.1778 -0.2794)
						)
						(arc
							(start 0.1778 -0.2794)
							(mid 0.249642 -0.249642)
							(end 0.2794 -0.1778)
						)
						(arc
							(start 0.2794 0.1778)
							(mid 0.249642 0.249642)
							(end 0.1778 0.2794)
						)
					)
					(width 0)
					(fill yes)
				)
			)
		)
	)
	(footprint ""
		(layer "B.Cu")
		(at 88.646 -3.429)
		(property "Reference" "SC1039"
			(at 0 0 0)
			(layer "B.SilkS")
			(hide yes)
			(effects
				(font
					(size 1.27 1.27)
				)
				(justify mirror)
			)
		)
		(property "Value" "SCD1U16V2KX-3GP"
			(at -1.1811 -2.7051 0)
			(unlocked yes)
			(layer "B.Fab")
			(hide yes)
			(effects
				(font
					(size 1.016 1.016)
					(thickness 0.1524)
				)
				(justify mirror)
			)
		)
		(property "Device Type" "C402H22"
			(at -1.1811 -4.2291 0)
			(unlocked yes)
			(layer "B.Fab")
			(hide yes)
			(effects
				(font
					(size 1.016 1.016)
					(thickness 0.1524)
				)
				(justify mirror)
			)
		)
		(duplicate_pad_numbers_are_jumpers no)
		(fp_rect
			(start 0.4318 0.9525)
			(end -0.4318 -0.9525)
			(stroke
				(width 0)
				(type default)
			)
			(fill no)
			(layer "B.CrtYd")
		)
		(fp_rect
			(start 0.4318 0.9525)
			(end -0.4318 -0.9525)
			(stroke
				(width 0)
				(type default)
			)
			(fill no)
			(layer "B.Fab")
		)
		(pad "1" smd custom
			(at 0 -0.4445 180)
			(size 0.1524 0.1524)
			(layers "B.Cu" "B.Mask" "B.Paste")
			(net "P0V955_C")
			(options
				(clearance outline)
				(anchor circle)
			)
			(primitives
				(gr_poly
					(pts
						(arc
							(start 0.3048 0.2032)
							(mid 0.275042 0.275042)
							(end 0.2032 0.3048)
						)
						(arc
							(start -0.2032 0.3048)
							(mid -0.275042 0.275042)
							(end -0.3048 0.2032)
						)
						(arc
							(start -0.3048 -0.2032)
							(mid -0.275042 -0.275042)
							(end -0.2032 -0.3048)
						)
						(arc
							(start 0.2032 -0.3048)
							(mid 0.275042 -0.275042)
							(end 0.3048 -0.2032)
						)
					)
					(width 0)
					(fill yes)
				)
			)
		)
		(pad "2" smd custom
			(at 0 0.4445 180)
			(size 0.1524 0.1524)
			(layers "B.Cu" "B.Mask" "B.Paste")
			(net "GND")
			(options
				(clearance outline)
				(anchor circle)
			)
			(primitives
				(gr_poly
					(pts
						(arc
							(start 0.3048 0.2032)
							(mid 0.275042 0.275042)
							(end 0.2032 0.3048)
						)
						(arc
							(start -0.2032 0.3048)
							(mid -0.275042 0.275042)
							(end -0.3048 0.2032)
						)
						(arc
							(start -0.3048 -0.2032)
							(mid -0.275042 -0.275042)
							(end -0.2032 -0.3048)
						)
						(arc
							(start 0.2032 -0.3048)
							(mid 0.275042 -0.275042)
							(end 0.3048 -0.2032)
						)
					)
					(width 0)
					(fill yes)
				)
			)
		)
	)
	(footprint ""
		(layer "B.Cu")
		(at 318.008 -166.878 -90)
		(property "Reference" "R242"
			(at 0 0 90)
			(layer "B.SilkS")
			(hide yes)
			(effects
				(font
					(size 1.27 1.27)
				)
				(justify mirror)
			)
		)
		(property "Value" "0R2J-2-GP"
			(at -0.064008 -3.993896 270)
			(unlocked yes)
			(layer "B.Fab")
			(hide yes)
			(effects
				(font
					(size 1.016 1.016)
					(thickness 0.1524)
				)
				(justify mirror)
			)
		)
		(property "Device Type" "R402H16"
			(at -0.064008 -5.517896 270)
			(unlocked yes)
			(layer "B.Fab")
			(hide yes)
			(effects
				(font
					(size 1.016 1.016)
					(thickness 0.1524)
				)
				(justify mirror)
			)
		)
		(duplicate_pad_numbers_are_jumpers no)
		(fp_line
			(start -0.508 -0.9398)
			(end 0.508 -0.9398)
			(stroke
				(width 0.1524)
				(type default)
			)
			(layer "B.SilkS")
		)
		(fp_line
			(start 0.508 -0.9398)
			(end 0.508 0.9398)
			(stroke
				(width 0.1524)
				(type default)
			)
			(layer "B.SilkS")
		)
		(fp_rect
			(start 0.508 0.9398)
			(end -0.508 -0.9398)
			(stroke
				(width 0)
				(type default)
			)
			(fill no)
			(layer "B.CrtYd")
		)
		(fp_rect
			(start 0.508 0.9398)
			(end -0.508 -0.9398)
			(stroke
				(width 0)
				(type default)
			)
			(fill no)
			(layer "B.Fab")
		)
		(pad "1" smd custom
			(at 0 -0.4445 90)
			(size 0.1397 0.1397)
			(layers "B.Cu" "B.Mask" "B.Paste")
			(net "BMC_I2C_D_SCL")
			(options
				(clearance outline)
				(anchor circle)
			)
			(primitives
				(gr_poly
					(pts
						(arc
							(start -0.1778 0.2794)
							(mid -0.249642 0.249642)
							(end -0.2794 0.1778)
						)
						(arc
							(start -0.2794 -0.1778)
							(mid -0.249642 -0.249642)
							(end -0.1778 -0.2794)
						)
						(arc
							(start 0.1778 -0.2794)
							(mid 0.249642 -0.249642)
							(end 0.2794 -0.1778)
						)
						(arc
							(start 0.2794 0.1778)
							(mid 0.249642 0.249642)
							(end 0.1778 0.2794)
						)
					)
					(width 0)
					(fill yes)
				)
			)
		)
		(pad "2" smd custom
			(at 0 0.4445 90)
			(size 0.1397 0.1397)
			(layers "B.Cu" "B.Mask" "B.Paste")
			(net "BMC0_SMB3_CLK")
			(options
				(clearance outline)
				(anchor circle)
			)
			(primitives
				(gr_poly
					(pts
						(arc
							(start -0.1778 0.2794)
							(mid -0.249642 0.249642)
							(end -0.2794 0.1778)
						)
						(arc
							(start -0.2794 -0.1778)
							(mid -0.249642 -0.249642)
							(end -0.1778 -0.2794)
						)
						(arc
							(start 0.1778 -0.2794)
							(mid 0.249642 -0.249642)
							(end 0.2794 -0.1778)
						)
						(arc
							(start 0.2794 0.1778)
							(mid 0.249642 0.249642)
							(end 0.1778 0.2794)
						)
					)
					(width 0)
					(fill yes)
				)
			)
		)
	)
	(footprint ""
		(layer "B.Cu")
		(at 79.871062 -62.700408)
		(property "Reference" "SR711"
			(at 0 0 0)
			(layer "B.SilkS")
			(hide yes)
			(effects
				(font
					(size 1.27 1.27)
				)
				(justify mirror)
			)
		)
		(property "Value" "10R2F-L-GP"
			(at -0.064008 -3.993896 0)
			(unlocked yes)
			(layer "B.Fab")
			(hide yes)
			(effects
				(font
					(size 1.016 1.016)
					(thickness 0.1524)
				)
				(justify mirror)
			)
		)
		(property "Device Type" "R402H14"
			(at -0.064008 -5.517896 0)
			(unlocked yes)
			(layer "B.Fab")
			(hide yes)
			(effects
				(font
					(size 1.016 1.016)
					(thickness 0.1524)
				)
				(justify mirror)
			)
		)
		(duplicate_pad_numbers_are_jumpers no)
		(fp_line
			(start -0.508 -0.9398)
			(end 0.508 -0.9398)
			(stroke
				(width 0.1524)
				(type default)
			)
			(layer "B.SilkS")
		)
		(fp_line
			(start 0.508 -0.9398)
			(end 0.508 0.9398)
			(stroke
				(width 0.1524)
				(type default)
			)
			(layer "B.SilkS")
		)
		(fp_rect
			(start 0.508 0.9398)
			(end -0.508 -0.9398)
			(stroke
				(width 0)
				(type default)
			)
			(fill no)
			(layer "B.CrtYd")
		)
		(fp_rect
			(start 0.508 0.9398)
			(end -0.508 -0.9398)
			(stroke
				(width 0)
				(type default)
			)
			(fill no)
			(layer "B.Fab")
		)
		(pad "1" smd custom
			(at 0 -0.4445 180)
			(size 0.1397 0.1397)
			(layers "B.Cu" "B.Mask" "B.Paste")
			(net "P1V8_C")
			(options
				(clearance outline)
				(anchor circle)
			)
			(primitives
				(gr_poly
					(pts
						(arc
							(start -0.1778 0.2794)
							(mid -0.249642 0.249642)
							(end -0.2794 0.1778)
						)
						(arc
							(start -0.2794 -0.1778)
							(mid -0.249642 -0.249642)
							(end -0.1778 -0.2794)
						)
						(arc
							(start 0.1778 -0.2794)
							(mid 0.249642 -0.249642)
							(end 0.2794 -0.1778)
						)
						(arc
							(start 0.2794 0.1778)
							(mid 0.249642 0.249642)
							(end 0.1778 0.2794)
						)
					)
					(width 0)
					(fill yes)
				)
			)
		)
		(pad "2" smd custom
			(at 0 0.4445 180)
			(size 0.1397 0.1397)
			(layers "B.Cu" "B.Mask" "B.Paste")
			(net "VDDA_SAS_REF_CLK")
			(options
				(clearance outline)
				(anchor circle)
			)
			(primitives
				(gr_poly
					(pts
						(arc
							(start -0.1778 0.2794)
							(mid -0.249642 0.249642)
							(end -0.2794 0.1778)
						)
						(arc
							(start -0.2794 -0.1778)
							(mid -0.249642 -0.249642)
							(end -0.1778 -0.2794)
						)
						(arc
							(start 0.1778 -0.2794)
							(mid 0.249642 -0.249642)
							(end 0.2794 -0.1778)
						)
						(arc
							(start 0.2794 0.1778)
							(mid 0.249642 0.249642)
							(end 0.1778 0.2794)
						)
					)
					(width 0)
					(fill yes)
				)
			)
		)
	)
	(footprint ""
		(layer "B.Cu")
		(at 110.776766 -46.6852 -90)
		(property "Reference" "SC993"
			(at 0 0 90)
			(layer "B.SilkS")
			(hide yes)
			(effects
				(font
					(size 1.27 1.27)
				)
				(justify mirror)
			)
		)
		(property "Value" "SCD1U16V2KX-3GP"
			(at -1.1811 -2.7051 270)
			(unlocked yes)
			(layer "B.Fab")
			(hide yes)
			(effects
				(font
					(size 1.016 1.016)
					(thickness 0.1524)
				)
				(justify mirror)
			)
		)
		(property "Device Type" "C402H22"
			(at -1.1811 -4.2291 270)
			(unlocked yes)
			(layer "B.Fab")
			(hide yes)
			(effects
				(font
					(size 1.016 1.016)
					(thickness 0.1524)
				)
				(justify mirror)
			)
		)
		(duplicate_pad_numbers_are_jumpers no)
		(fp_rect
			(start 0.4318 0.9525)
			(end -0.4318 -0.9525)
			(stroke
				(width 0)
				(type default)
			)
			(fill no)
			(layer "B.CrtYd")
		)
		(fp_rect
			(start 0.4318 0.9525)
			(end -0.4318 -0.9525)
			(stroke
				(width 0)
				(type default)
			)
			(fill no)
			(layer "B.Fab")
		)
		(pad "1" smd custom
			(at 0 -0.4445 90)
			(size 0.1524 0.1524)
			(layers "B.Cu" "B.Mask" "B.Paste")
			(net "P1V8_C")
			(options
				(clearance outline)
				(anchor circle)
			)
			(primitives
				(gr_poly
					(pts
						(arc
							(start 0.3048 0.2032)
							(mid 0.275042 0.275042)
							(end 0.2032 0.3048)
						)
						(arc
							(start -0.2032 0.3048)
							(mid -0.275042 0.275042)
							(end -0.3048 0.2032)
						)
						(arc
							(start -0.3048 -0.2032)
							(mid -0.275042 -0.275042)
							(end -0.2032 -0.3048)
						)
						(arc
							(start 0.2032 -0.3048)
							(mid 0.275042 -0.275042)
							(end 0.3048 -0.2032)
						)
					)
					(width 0)
					(fill yes)
				)
			)
		)
		(pad "2" smd custom
			(at 0 0.4445 90)
			(size 0.1524 0.1524)
			(layers "B.Cu" "B.Mask" "B.Paste")
			(net "GND")
			(options
				(clearance outline)
				(anchor circle)
			)
			(primitives
				(gr_poly
					(pts
						(arc
							(start 0.3048 0.2032)
							(mid 0.275042 0.275042)
							(end 0.2032 0.3048)
						)
						(arc
							(start -0.2032 0.3048)
							(mid -0.275042 0.275042)
							(end -0.3048 0.2032)
						)
						(arc
							(start -0.3048 -0.2032)
							(mid -0.275042 -0.275042)
							(end -0.2032 -0.3048)
						)
						(arc
							(start 0.2032 -0.3048)
							(mid 0.275042 -0.275042)
							(end 0.3048 -0.2032)
						)
					)
					(width 0)
					(fill yes)
				)
			)
		)
	)
	(footprint ""
		(layer "B.Cu")
		(at 103.359966 -44.958 90)
		(property "Reference" "SC1024"
			(at 0 0 90)
			(layer "B.SilkS")
			(hide yes)
			(effects
				(font
					(size 1.27 1.27)
				)
				(justify mirror)
			)
		)
		(property "Value" "SC1U10V2KX-4-GP"
			(at -1.1811 -2.7051 90)
			(unlocked yes)
			(layer "B.Fab")
			(hide yes)
			(effects
				(font
					(size 1.016 1.016)
					(thickness 0.1524)
				)
				(justify mirror)
			)
		)
		(property "Device Type" "C402H22"
			(at -1.1811 -4.2291 90)
			(unlocked yes)
			(layer "B.Fab")
			(hide yes)
			(effects
				(font
					(size 1.016 1.016)
					(thickness 0.1524)
				)
				(justify mirror)
			)
		)
		(duplicate_pad_numbers_are_jumpers no)
		(fp_rect
			(start 0.4318 0.9525)
			(end -0.4318 -0.9525)
			(stroke
				(width 0)
				(type default)
			)
			(fill no)
			(layer "B.CrtYd")
		)
		(fp_rect
			(start 0.4318 0.9525)
			(end -0.4318 -0.9525)
			(stroke
				(width 0)
				(type default)
			)
			(fill no)
			(layer "B.Fab")
		)
		(pad "1" smd custom
			(at 0 -0.4445 270)
			(size 0.1524 0.1524)
			(layers "B.Cu" "B.Mask" "B.Paste")
			(net "P0V955_C")
			(options
				(clearance outline)
				(anchor circle)
			)
			(primitives
				(gr_poly
					(pts
						(arc
							(start 0.3048 0.2032)
							(mid 0.275042 0.275042)
							(end 0.2032 0.3048)
						)
						(arc
							(start -0.2032 0.3048)
							(mid -0.275042 0.275042)
							(end -0.3048 0.2032)
						)
						(arc
							(start -0.3048 -0.2032)
							(mid -0.275042 -0.275042)
							(end -0.2032 -0.3048)
						)
						(arc
							(start 0.2032 -0.3048)
							(mid 0.275042 -0.275042)
							(end 0.3048 -0.2032)
						)
					)
					(width 0)
					(fill yes)
				)
			)
		)
		(pad "2" smd custom
			(at 0 0.4445 270)
			(size 0.1524 0.1524)
			(layers "B.Cu" "B.Mask" "B.Paste")
			(net "GND")
			(options
				(clearance outline)
				(anchor circle)
			)
			(primitives
				(gr_poly
					(pts
						(arc
							(start 0.3048 0.2032)
							(mid 0.275042 0.275042)
							(end 0.2032 0.3048)
						)
						(arc
							(start -0.2032 0.3048)
							(mid -0.275042 0.275042)
							(end -0.3048 0.2032)
						)
						(arc
							(start -0.3048 -0.2032)
							(mid -0.275042 -0.275042)
							(end -0.2032 -0.3048)
						)
						(arc
							(start 0.2032 -0.3048)
							(mid 0.275042 -0.275042)
							(end 0.3048 -0.2032)
						)
					)
					(width 0)
					(fill yes)
				)
			)
		)
	)
)
